(kicad_pcb
	(version 20241229)
	(generator "pcbnew")
	(generator_version "9.0")
	(general
		(thickness 1.599998)
		(legacy_teardrops no)
	)
	(paper "A4")
	(title_block
		(date "2023-02-12")
		(rev "1.1.5")
		(comment 9 "footprints 173-178 of 473")
	)
	(layers
		(0 "F.Cu" signal)
		(4 "In1.Cu" power "In1.GND")
		(6 "In2.Cu" signal)
		(8 "In3.Cu" power "In3.GND")
		(10 "In4.Cu" power "In4.VCC")
		(12 "In5.Cu" signal)
		(14 "In6.Cu" power "In6.VCC")
		(2 "B.Cu" signal)
		(9 "F.Adhes" user "F.Adhesive")
		(11 "B.Adhes" user "B.Adhesive")
		(13 "F.Paste" user)
		(15 "B.Paste" user)
		(5 "F.SilkS" user "F.Silkscreen")
		(7 "B.SilkS" user "B.Silkscreen")
		(1 "F.Mask" user)
		(3 "B.Mask" user)
		(17 "Dwgs.User" user "User.Drawings")
		(19 "Cmts.User" user "User.Comments")
		(21 "Eco1.User" user "User.Eco1")
		(23 "Eco2.User" user "User.Eco2")
		(25 "Edge.Cuts" user)
		(27 "Margin" user)
		(31 "F.CrtYd" user "F.Courtyard")
		(29 "B.CrtYd" user "B.Courtyard")
		(35 "F.Fab" user)
		(33 "B.Fab" user)
	)
	(footprint "antmicro-footprints:C_0603_1608Metric"
		(layer "F.Cu")
		(at 120.0492 110.475 180)
		(descr "Capacitor SMD 0603")
		(tags "capacitor 0603")
		(property "Reference" "C148"
			(at 3.7492 -0.425 180)
			(layer "F.SilkS")
			(effects
				(font
					(size 0.7 0.7)
					(thickness 0.15)
				)
				(justify left bottom)
			)
		)
		(property "Value" "C_47u_0603"
			(at 0 1.6 180)
			(layer "F.Fab")
			(effects
				(font
					(size 0.7 0.7)
					(thickness 0.15)
				)
				(justify left bottom)
			)
		)
		(property "Description" " "
			(at 0 0 180)
			(layer "F.Fab")
			(hide yes)
			(effects
				(font
					(size 1.27 1.27)
					(thickness 0.15)
				)
			)
		)
		(property "Author" "Antmicro"
			(at 240.0984 220.95 0)
			(layer "F.Fab")
			(hide yes)
			(effects
				(font
					(size 1 1)
					(thickness 0.15)
				)
			)
		)
		(property "Dielectric" ""
			(at 240.0984 220.95 0)
			(layer "F.Fab")
			(hide yes)
			(effects
				(font
					(size 1 1)
					(thickness 0.15)
				)
			)
		)
		(property "License" "Apache-2.0"
			(at 240.0984 220.95 0)
			(layer "F.Fab")
			(hide yes)
			(effects
				(font
					(size 1 1)
					(thickness 0.15)
				)
			)
		)
		(property "MPN" "GRM188R60J476ME15D"
			(at 240.0984 220.95 0)
			(layer "F.Fab")
			(hide yes)
			(effects
				(font
					(size 1 1)
					(thickness 0.15)
				)
			)
		)
		(property "Manufacturer" "Murata"
			(at 240.0984 220.95 0)
			(layer "F.Fab")
			(hide yes)
			(effects
				(font
					(size 1 1)
					(thickness 0.15)
				)
			)
		)
		(property "Val" "47u"
			(at 240.0984 220.95 0)
			(layer "F.Fab")
			(hide yes)
			(effects
				(font
					(size 1 1)
					(thickness 0.15)
				)
			)
		)
		(property "Voltage" ""
			(at 240.0984 220.95 0)
			(layer "F.Fab")
			(hide yes)
			(effects
				(font
					(size 1 1)
					(thickness 0.15)
				)
			)
		)
		(sheetname "Supply")
		(sheetfile "supply.kicad_sch")
		(attr smd)
		(fp_line
			(start -0.3 0.3)
			(end 0.3 0.3)
			(stroke
				(width 0.15)
				(type solid)
			)
			(layer "F.SilkS")
		)
		(fp_line
			(start -0.3 -0.3)
			(end 0.3 -0.3)
			(stroke
				(width 0.15)
				(type solid)
			)
			(layer "F.SilkS")
		)
		(fp_rect
			(start -1.24 -0.7)
			(end 1.24 0.7)
			(stroke
				(width 0.05)
				(type solid)
			)
			(fill no)
			(layer "F.CrtYd")
		)
		(fp_rect
			(start -0.8 -0.4)
			(end 0.8 0.4)
			(stroke
				(width 0.15)
				(type solid)
			)
			(fill no)
			(layer "F.Fab")
		)
		(pad "1" smd roundrect
			(at -0.7 0 180)
			(size 0.6 0.8)
			(layers "F.Cu" "F.Mask" "F.Paste")
			(roundrect_rratio 0.2)
			(net 55 "Net-(C141-Pad1)")
			(pintype "passive")
		)
		(pad "2" smd roundrect
			(at 0.7 0 180)
			(size 0.6 0.8)
			(layers "F.Cu" "F.Mask" "F.Paste")
			(roundrect_rratio 0.2)
			(net 5 "GND")
			(pintype "passive")
		)
	)
	(footprint "antmicro-footprints:C_0603_1608Metric"
		(layer "F.Cu")
		(at 120.0492 111.975 180)
		(descr "Capacitor SMD 0603")
		(tags "capacitor 0603")
		(property "Reference" "C145"
			(at 3.7492 -0.425 180)
			(layer "F.SilkS")
			(effects
				(font
					(size 0.7 0.7)
					(thickness 0.15)
				)
				(justify left bottom)
			)
		)
		(property "Value" "C_47u_0603"
			(at 0 1.6 180)
			(layer "F.Fab")
			(effects
				(font
					(size 0.7 0.7)
					(thickness 0.15)
				)
				(justify left bottom)
			)
		)
		(property "Description" " "
			(at 0 0 180)
			(layer "F.Fab")
			(hide yes)
			(effects
				(font
					(size 1.27 1.27)
					(thickness 0.15)
				)
			)
		)
		(property "Author" "Antmicro"
			(at 240.0984 223.95 0)
			(layer "F.Fab")
			(hide yes)
			(effects
				(font
					(size 1 1)
					(thickness 0.15)
				)
			)
		)
		(property "Dielectric" ""
			(at 240.0984 223.95 0)
			(layer "F.Fab")
			(hide yes)
			(effects
				(font
					(size 1 1)
					(thickness 0.15)
				)
			)
		)
		(property "License" "Apache-2.0"
			(at 240.0984 223.95 0)
			(layer "F.Fab")
			(hide yes)
			(effects
				(font
					(size 1 1)
					(thickness 0.15)
				)
			)
		)
		(property "MPN" "GRM188R60J476ME15D"
			(at 240.0984 223.95 0)
			(layer "F.Fab")
			(hide yes)
			(effects
				(font
					(size 1 1)
					(thickness 0.15)
				)
			)
		)
		(property "Manufacturer" "Murata"
			(at 240.0984 223.95 0)
			(layer "F.Fab")
			(hide yes)
			(effects
				(font
					(size 1 1)
					(thickness 0.15)
				)
			)
		)
		(property "Val" "47u"
			(at 240.0984 223.95 0)
			(layer "F.Fab")
			(hide yes)
			(effects
				(font
					(size 1 1)
					(thickness 0.15)
				)
			)
		)
		(property "Voltage" ""
			(at 240.0984 223.95 0)
			(layer "F.Fab")
			(hide yes)
			(effects
				(font
					(size 1 1)
					(thickness 0.15)
				)
			)
		)
		(sheetname "Supply")
		(sheetfile "supply.kicad_sch")
		(attr smd)
		(fp_line
			(start -0.3 0.3)
			(end 0.3 0.3)
			(stroke
				(width 0.15)
				(type solid)
			)
			(layer "F.SilkS")
		)
		(fp_line
			(start -0.3 -0.3)
			(end 0.3 -0.3)
			(stroke
				(width 0.15)
				(type solid)
			)
			(layer "F.SilkS")
		)
		(fp_rect
			(start -1.24 -0.7)
			(end 1.24 0.7)
			(stroke
				(width 0.05)
				(type solid)
			)
			(fill no)
			(layer "F.CrtYd")
		)
		(fp_rect
			(start -0.8 -0.4)
			(end 0.8 0.4)
			(stroke
				(width 0.15)
				(type solid)
			)
			(fill no)
			(layer "F.Fab")
		)
		(pad "1" smd roundrect
			(at -0.7 0 180)
			(size 0.6 0.8)
			(layers "F.Cu" "F.Mask" "F.Paste")
			(roundrect_rratio 0.2)
			(net 55 "Net-(C141-Pad1)")
			(pintype "passive")
		)
		(pad "2" smd roundrect
			(at 0.7 0 180)
			(size 0.6 0.8)
			(layers "F.Cu" "F.Mask" "F.Paste")
			(roundrect_rratio 0.2)
			(net 5 "GND")
			(pintype "passive")
		)
	)
	(footprint "antmicro-footprints:V-QFN2030-12"
		(layer "F.Cu")
		(at 115.188672 100.378992 180)
		(property "Reference" "U8"
			(at -1.011328 -2.521008 180)
			(layer "F.SilkS")
			(effects
				(font
					(size 0.7 0.7)
					(thickness 0.15)
				)
				(justify left bottom)
			)
		)
		(property "Value" "AP62600SJ-7"
			(at -4 2.2 180)
			(layer "F.Fab")
			(effects
				(font
					(size 0.7 0.7)
					(thickness 0.15)
				)
				(justify left bottom)
			)
		)
		(property "Description" "Buck Switching Regulator IC Positive Fixed 0.6V 1 Output 6A 12-VFQFN"
			(at 0 0 180)
			(layer "F.Fab")
			(hide yes)
			(effects
				(font
					(size 1.27 1.27)
					(thickness 0.15)
				)
			)
		)
		(property "Author" "Antmicro"
			(at 230.377344 200.757984 0)
			(layer "F.Fab")
			(hide yes)
			(effects
				(font
					(size 1 1)
					(thickness 0.15)
				)
			)
		)
		(property "License" "Apache-2.0"
			(at 230.377344 200.757984 0)
			(layer "F.Fab")
			(hide yes)
			(effects
				(font
					(size 1 1)
					(thickness 0.15)
				)
			)
		)
		(property "MPN" "AP62600SJ-7"
			(at 230.377344 200.757984 0)
			(layer "F.Fab")
			(hide yes)
			(effects
				(font
					(size 1 1)
					(thickness 0.15)
				)
			)
		)
		(property "Manufacturer" "Diodes Incorporated"
			(at 230.377344 200.757984 0)
			(layer "F.Fab")
			(hide yes)
			(effects
				(font
					(size 1 1)
					(thickness 0.15)
				)
			)
		)
		(sheetname "Supply")
		(sheetfile "supply.kicad_sch")
		(attr smd)
		(fp_line
			(start 1.8 1.199)
			(end 0.8 1.199)
			(stroke
				(width 0.15)
				(type solid)
			)
			(layer "F.SilkS")
		)
		(fp_line
			(start 1.8 0.998)
			(end 1.8 1.199)
			(stroke
				(width 0.15)
				(type solid)
			)
			(layer "F.SilkS")
		)
		(fp_line
			(start 1.8 -1.276)
			(end 1.8 -1.025)
			(stroke
				(width 0.15)
				(type solid)
			)
			(layer "F.SilkS")
		)
		(fp_line
			(start -0.802 1.199)
			(end -1.801 1.199)
			(stroke
				(width 0.15)
				(type solid)
			)
			(layer "F.SilkS")
		)
		(fp_line
			(start -1.801 1.199)
			(end -1.801 0.998)
			(stroke
				(width 0.15)
				(type solid)
			)
			(layer "F.SilkS")
		)
		(fp_line
			(start -1.801 -1)
			(end -1.801 -1.2)
			(stroke
				(width 0.15)
				(type solid)
			)
			(layer "F.SilkS")
		)
		(fp_line
			(start -1.801 -1.2)
			(end -0.802 -1.2)
			(stroke
				(width 0.15)
				(type solid)
			)
			(layer "F.SilkS")
		)
		(fp_circle
			(center 0.497 -1.7)
			(end 0.548 -1.7)
			(stroke
				(width 0.15)
				(type solid)
			)
			(fill yes)
			(layer "F.SilkS")
		)
		(fp_rect
			(start -2.026 -1.525)
			(end 2.023 1.524)
			(stroke
				(width 0.05)
				(type solid)
			)
			(fill no)
			(layer "F.CrtYd")
		)
		(fp_line
			(start 1.3 -1)
			(end 1.5 -0.8)
			(stroke
				(width 0.15)
				(type solid)
			)
			(layer "F.Fab")
		)
		(fp_rect
			(start -1.526 -1.025)
			(end 1.523 1.024)
			(stroke
				(width 0.15)
				(type solid)
			)
			(fill no)
			(layer "F.Fab")
		)
		(pad "1" smd rect
			(at 0.498 -0.552 90)
			(size 1.6 0.35)
			(layers "F.Cu" "F.Mask" "F.Paste")
			(net 5 "GND")
			(pinfunction "PGND")
			(pintype "passive")
		)
		(pad "2" smd rect
			(at -0.5 -0.552 90)
			(size 1.6 0.35)
			(layers "F.Cu" "F.Mask" "F.Paste")
			(net 463 "VCC5V0_INT")
			(pinfunction "VIN")
			(pintype "power_in")
		)
		(pad "3" smd rect
			(at -1.45 -0.75 90)
			(size 0.35 0.8)
			(layers "F.Cu" "F.Mask" "F.Paste")
			(net 577 "/Supply/3V3_EN")
			(pinfunction "EN")
			(pintype "input")
		)
		(pad "4" smd rect
			(at -1.45 -0.25 90)
			(size 0.35 0.8)
			(layers "F.Cu" "F.Mask" "F.Paste")
			(net 617 "/Supply/3V3_MODE")
			(pinfunction "MODE")
			(pintype "input")
		)
		(pad "5" smd rect
			(at -1.45 0.248 90)
			(size 0.35 0.8)
			(layers "F.Cu" "F.Mask" "F.Paste")
			(net 610 "/Supply/3V3_FSEL")
			(pinfunction "FSEL")
			(pintype "input")
		)
		(pad "6" smd rect
			(at -1.45 0.748 90)
			(size 0.35 0.8)
			(layers "F.Cu" "F.Mask" "F.Paste")
			(net 647 "unconnected-(U8-PG-Pad6)")
			(pinfunction "PG")
			(pintype "open_collector+no_connect")
		)
		(pad "7" smd rect
			(at -0.5 0.949 180)
			(size 0.35 0.8)
			(layers "F.Cu" "F.Mask" "F.Paste")
			(net 574 "/Supply/3V3_BST")
			(pinfunction "BST")
			(pintype "input")
		)
		(pad "8" smd rect
			(at 0 0.55 90)
			(size 1.6 0.35)
			(layers "F.Cu" "F.Mask" "F.Paste")
			(net 575 "/Supply/3V3_SW")
			(pinfunction "SW")
			(pintype "output")
		)
		(pad "9" smd rect
			(at 1.449 0.748 270)
			(size 0.35 0.8)
			(layers "F.Cu" "F.Mask" "F.Paste")
			(net 609 "/Supply/3V3_VCC_INT")
			(pinfunction "VCC")
			(pintype "input")
		)
		(pad "10" smd rect
			(at 1.449 0.248 270)
			(size 0.35 0.8)
			(layers "F.Cu" "F.Mask" "F.Paste")
			(net 618 "/Supply/3V3_SS{slash}TR")
			(pinfunction "SS/TR")
			(pintype "input")
		)
		(pad "11" smd rect
			(at 1.449 -0.25 270)
			(size 0.35 0.8)
			(layers "F.Cu" "F.Mask" "F.Paste")
			(net 5 "GND")
			(pinfunction "GND")
			(pintype "passive")
		)
		(pad "12" smd rect
			(at 1.449 -0.75 270)
			(size 0.35 0.8)
			(layers "F.Cu" "F.Mask" "F.Paste")
			(net 578 "/Supply/3V3_FB")
			(pinfunction "FB")
			(pintype "input")
		)
	)
	(footprint "antmicro-footprints:C_0402_1005Metric"
		(layer "F.Cu")
		(at 111.147806 83.774 180)
		(descr "Capacitor SMD 0402")
		(tags "capacitor SMD 0402")
		(property "Reference" "C178"
			(at 3.647806 -0.326 180)
			(layer "F.SilkS")
			(effects
				(font
					(size 0.7 0.7)
					(thickness 0.15)
				)
				(justify left bottom)
			)
		)
		(property "Value" "C_1u_0402"
			(at 0 1.4 180)
			(layer "F.Fab")
			(effects
				(font
					(size 0.7 0.7)
					(thickness 0.15)
				)
				(justify left bottom)
			)
		)
		(property "Description" " "
			(at 0 0 180)
			(layer "F.Fab")
			(hide yes)
			(effects
				(font
					(size 1.27 1.27)
					(thickness 0.15)
				)
			)
		)
		(property "Author" "Antmicro"
			(at 222.295612 167.548 0)
			(layer "F.Fab")
			(hide yes)
			(effects
				(font
					(size 1 1)
					(thickness 0.15)
				)
			)
		)
		(property "Dielectric" ""
			(at 222.295612 167.548 0)
			(layer "F.Fab")
			(hide yes)
			(effects
				(font
					(size 1 1)
					(thickness 0.15)
				)
			)
		)
		(property "License" "Apache-2.0"
			(at 222.295612 167.548 0)
			(layer "F.Fab")
			(hide yes)
			(effects
				(font
					(size 1 1)
					(thickness 0.15)
				)
			)
		)
		(property "MPN" "C1005X6S1A105K050BC"
			(at 222.295612 167.548 0)
			(layer "F.Fab")
			(hide yes)
			(effects
				(font
					(size 1 1)
					(thickness 0.15)
				)
			)
		)
		(property "Manufacturer" "TDK"
			(at 222.295612 167.548 0)
			(layer "F.Fab")
			(hide yes)
			(effects
				(font
					(size 1 1)
					(thickness 0.15)
				)
			)
		)
		(property "Val" "1u"
			(at 222.295612 167.548 0)
			(layer "F.Fab")
			(hide yes)
			(effects
				(font
					(size 1 1)
					(thickness 0.15)
				)
			)
		)
		(property "Voltage" ""
			(at 222.295612 167.548 0)
			(layer "F.Fab")
			(hide yes)
			(effects
				(font
					(size 1 1)
					(thickness 0.15)
				)
			)
		)
		(sheetname "Supply")
		(sheetfile "supply.kicad_sch")
		(attr smd)
		(fp_rect
			(start -0.94 -0.47)
			(end 0.94 0.47)
			(stroke
				(width 0.05)
				(type solid)
			)
			(fill no)
			(layer "F.CrtYd")
		)
		(fp_rect
			(start -0.499 -0.249)
			(end 0.499 0.249)
			(stroke
				(width 0.15)
				(type solid)
			)
			(fill no)
			(layer "F.Fab")
		)
		(pad "1" smd roundrect
			(at -0.484 0 180)
			(size 0.59 0.64)
			(layers "F.Cu" "F.Mask" "F.Paste")
			(roundrect_rratio 0.25)
			(net 583 "/Supply/1V8_REG")
			(pintype "passive")
		)
		(pad "2" smd roundrect
			(at 0.484 0 180)
			(size 0.59 0.64)
			(layers "F.Cu" "F.Mask" "F.Paste")
			(roundrect_rratio 0.25)
			(net 5 "GND")
			(pintype "passive")
		)
	)
	(footprint "antmicro-footprints:L_WE-MAIA-2512"
		(layer "F.Cu")
		(at 190.3 114.385 90)
		(property "Reference" "L5"
			(at -2.709 0.2 0)
			(layer "F.SilkS")
			(effects
				(font
					(size 0.7 0.7)
					(thickness 0.15)
				)
				(justify left bottom)
			)
		)
		(property "Value" "784383240047"
			(at 0 2.3 90)
			(layer "F.Fab")
			(effects
				(font
					(size 0.7 0.7)
					(thickness 0.15)
				)
				(justify left bottom)
			)
		)
		(property "Description" "Power Inductor (SMT), AEC-Q200, 470 nH, 3.4 A, Shielded, 6.25 A, WE-MAIA"
			(at 0 0 90)
			(layer "F.Fab")
			(hide yes)
			(effects
				(font
					(size 1.27 1.27)
					(thickness 0.15)
				)
			)
		)
		(property "Author" "Antmicro"
			(at 304.685 -75.915 0)
			(layer "F.Fab")
			(hide yes)
			(effects
				(font
					(size 1 1)
					(thickness 0.15)
				)
			)
		)
		(property "IMax" "3.4 A"
			(at 304.685 -75.915 0)
			(layer "F.Fab")
			(hide yes)
			(effects
				(font
					(size 1 1)
					(thickness 0.15)
				)
			)
		)
		(property "ISat" "6.25 A"
			(at 304.685 -75.915 0)
			(layer "F.Fab")
			(hide yes)
			(effects
				(font
					(size 1 1)
					(thickness 0.15)
				)
			)
		)
		(property "License" "Apache-2.0"
			(at 304.685 -75.915 0)
			(layer "F.Fab")
			(hide yes)
			(effects
				(font
					(size 1 1)
					(thickness 0.15)
				)
			)
		)
		(property "MPN" "784383240047"
			(at 304.685 -75.915 0)
			(layer "F.Fab")
			(hide yes)
			(effects
				(font
					(size 1 1)
					(thickness 0.15)
				)
			)
		)
		(property "Manufacturer" "Würth Elektronik"
			(at 304.685 -75.915 0)
			(layer "F.Fab")
			(hide yes)
			(effects
				(font
					(size 1 1)
					(thickness 0.15)
				)
			)
		)
		(property "Size" "2x2.5"
			(at 304.685 -75.915 0)
			(layer "F.Fab")
			(hide yes)
			(effects
				(font
					(size 1 1)
					(thickness 0.15)
				)
			)
		)
		(property "Val" "470n/3.4A"
			(at 304.685 -75.915 0)
			(layer "F.Fab")
			(hide yes)
			(effects
				(font
					(size 1 1)
					(thickness 0.15)
				)
			)
		)
		(sheetname "Supply")
		(sheetfile "supply.kicad_sch")
		(attr smd)
		(fp_line
			(start -0.325 -1.125)
			(end 0.325 -1.125)
			(stroke
				(width 0.15)
				(type solid)
			)
			(layer "F.SilkS")
		)
		(fp_line
			(start -0.325 1.125)
			(end 0.325 1.125)
			(stroke
				(width 0.15)
				(type solid)
			)
			(layer "F.SilkS")
		)
		(fp_rect
			(start -1.65 -1.4)
			(end 1.65 1.4)
			(stroke
				(width 0.05)
				(type solid)
			)
			(fill no)
			(layer "F.CrtYd")
		)
		(fp_rect
			(start -1.25 -1)
			(end 1.25 1)
			(stroke
				(width 0.15)
				(type solid)
			)
			(fill no)
			(layer "F.Fab")
		)
		(pad "1" smd roundrect
			(at -0.975 0 90)
			(size 0.85 2.3)
			(layers "F.Cu" "F.Mask" "F.Paste")
			(roundrect_rratio 0.1)
			(net 586 "/Supply/1V2_SW")
			(pintype "passive")
		)
		(pad "2" smd roundrect
			(at 0.975 0 90)
			(size 0.85 2.3)
			(layers "F.Cu" "F.Mask" "F.Paste")
			(roundrect_rratio 0.1)
			(net 589 "/Supply/1V2_REG")
			(pintype "passive")
		)
	)
	(footprint "antmicro-footprints:C_0402_1005Metric"
		(layer "F.Cu")
		(at 191.3 111.635 90)
		(descr "Capacitor SMD 0402")
		(tags "capacitor SMD 0402")
		(property "Reference" "C170"
			(at 0.735 0.4 90)
			(layer "F.SilkS")
			(effects
				(font
					(size 0.7 0.7)
					(thickness 0.15)
				)
				(justify left bottom)
			)
		)
		(property "Value" "C_22u_0402"
			(at 0 1.4 90)
			(layer "F.Fab")
			(effects
				(font
					(size 0.7 0.7)
					(thickness 0.15)
				)
				(justify left bottom)
			)
		)
		(property "Description" " "
			(at 0 0 90)
			(layer "F.Fab")
			(hide yes)
			(effects
				(font
					(size 1.27 1.27)
					(thickness 0.15)
				)
			)
		)
		(property "Author" "Antmicro"
			(at 302.935 -79.665 0)
			(layer "F.Fab")
			(hide yes)
			(effects
				(font
					(size 1 1)
					(thickness 0.15)
				)
			)
		)
		(property "Dielectric" ""
			(at 302.935 -79.665 0)
			(layer "F.Fab")
			(hide yes)
			(effects
				(font
					(size 1 1)
					(thickness 0.15)
				)
			)
		)
		(property "License" "Apache-2.0"
			(at 302.935 -79.665 0)
			(layer "F.Fab")
			(hide yes)
			(effects
				(font
					(size 1 1)
					(thickness 0.15)
				)
			)
		)
		(property "MPN" "04024W226MAT2A"
			(at 302.935 -79.665 0)
			(layer "F.Fab")
			(hide yes)
			(effects
				(font
					(size 1 1)
					(thickness 0.15)
				)
			)
		)
		(property "Manufacturer" "AVX"
			(at 302.935 -79.665 0)
			(layer "F.Fab")
			(hide yes)
			(effects
				(font
					(size 1 1)
					(thickness 0.15)
				)
			)
		)
		(property "Val" "22u"
			(at 302.935 -79.665 0)
			(layer "F.Fab")
			(hide yes)
			(effects
				(font
					(size 1 1)
					(thickness 0.15)
				)
			)
		)
		(property "Voltage" ""
			(at 302.935 -79.665 0)
			(layer "F.Fab")
			(hide yes)
			(effects
				(font
					(size 1 1)
					(thickness 0.15)
				)
			)
		)
		(sheetname "Supply")
		(sheetfile "supply.kicad_sch")
		(attr smd)
		(fp_rect
			(start -0.94 -0.47)
			(end 0.94 0.47)
			(stroke
				(width 0.05)
				(type solid)
			)
			(fill no)
			(layer "F.CrtYd")
		)
		(fp_rect
			(start -0.499 -0.249)
			(end 0.499 0.249)
			(stroke
				(width 0.15)
				(type solid)
			)
			(fill no)
			(layer "F.Fab")
		)
		(pad "1" smd roundrect
			(at -0.484 0 90)
			(size 0.59 0.64)
			(layers "F.Cu" "F.Mask" "F.Paste")
			(roundrect_rratio 0.25)
			(net 589 "/Supply/1V2_REG")
			(pintype "passive")
		)
		(pad "2" smd roundrect
			(at 0.484 0 90)
			(size 0.59 0.64)
			(layers "F.Cu" "F.Mask" "F.Paste")
			(roundrect_rratio 0.25)
			(net 5 "GND")
			(pintype "passive")
		)
	)
)
